# S9S_MB_2U (Grand Teton) — schematic netlist excerpt (pin names and nets, part order shuffled) for the footprints in the layout excerpt that follows; sources: Cadence DE-HDL packaged netlist, KiCad conversion of 03242023_DA0F0TMBIJ0_F0T_Motherboard_J_brd_V01_OCP.brd

R2383  Q_RES  1K 1% CHIP  pkg 0402LF  page 274 : A = P3V3_AUX ; B = PWRGD_PVCCINFAON_CPU0_R
R4780  Q_RES  0 5% CHIP  pkg 0402LF  page 262 : A = PWRGD_P1V05_PCH_AUX_R ; B = PWRGD_PVNN_PCH_AUX

(kicad_pcb
	(version 20260206)
	(generator "pcbnew")
	(generator_version "10.0")
	(general
		(thickness 1.6)
		(legacy_teardrops no)
	)
	(paper "A4")
	(title_block
		(title "03242023_DA0F0TMBIJ0_F0T_Motherboard_J_brd_V01_OCP.brd")
		(comment 1 "Grand Teton / footprints 5734-5735 of 6105")
	)
	(layers
		(0 "F.Cu" signal "TOP")
		(4 "In1.Cu" signal "GND")
		(6 "In2.Cu" signal "IN1")
		(8 "In3.Cu" signal "GND1")
		(10 "In4.Cu" signal "IN2")
		(12 "In5.Cu" signal "GND2")
		(14 "In6.Cu" signal "IN3")
		(16 "In7.Cu" signal "GND3")
		(18 "In8.Cu" signal "VCC")
		(20 "In9.Cu" signal "VCC1")
		(22 "In10.Cu" signal "GND4")
		(24 "In11.Cu" signal "IN4")
		(26 "In12.Cu" signal "GND5")
		(28 "In13.Cu" signal "IN5")
		(30 "In14.Cu" signal "GND6")
		(32 "In15.Cu" signal "IN6")
		(34 "In16.Cu" signal "GND7")
		(2 "B.Cu" signal "BOTTOM")
		(9 "F.Adhes" user "F.Adhesive")
		(11 "B.Adhes" user "B.Adhesive")
		(13 "F.Paste" user "Package Geometry/Pastemask Top")
		(15 "B.Paste" user "Package Geometry/Pastemask Bottom")
		(5 "F.SilkS" user "Ref Des/Silkscreen Top")
		(7 "B.SilkS" user "Ref Des/Silkscreen Bottom")
		(1 "F.Mask" user "Board Geometry/Soldermask Top")
		(3 "B.Mask" user "Board Geometry/Soldermask Bottom")
		(17 "Dwgs.User" user "User.Drawings")
		(19 "Cmts.User" user "User.Comments")
		(21 "Eco1.User" user "User.Eco1")
		(23 "Eco2.User" user "User.Eco2")
		(25 "Edge.Cuts" user "Board Geometry/Outline")
		(27 "Margin" user)
		(31 "F.CrtYd" user "Package Geometry/Place Bound Top")
		(29 "B.CrtYd" user "Package Geometry/Place Bound Bottom")
		(35 "F.Fab" user "Ref Des/Assembly Top")
		(33 "B.Fab" user "Ref Des/Assembly Bottom")
	)
	(footprint ""
		(layer "B.Cu")
		(at 430.600104 -132.462778)
		(property "Reference" "R2383"
			(at 0 0 0)
			(layer "B.SilkS")
			(hide yes)
			(effects
				(font
					(size 1.27 1.27)
				)
				(justify mirror)
			)
		)
		(property "Value" ""
			(at 0 0 0)
			(layer "B.Fab")
			(effects
				(font
					(size 1.27 1.27)
				)
				(justify mirror)
			)
		)
		(duplicate_pad_numbers_are_jumpers no)
		(fp_line
			(start -0.7874 -0.4064)
			(end -0.7874 0.4064)
			(stroke
				(width 0.1524)
				(type default)
			)
			(layer "B.SilkS")
		)
		(fp_line
			(start -0.7874 0.4064)
			(end 0.7874 0.4064)
			(stroke
				(width 0.1524)
				(type default)
			)
			(layer "B.SilkS")
		)
		(fp_line
			(start 0.7874 -0.4064)
			(end -0.7874 -0.4064)
			(stroke
				(width 0.1524)
				(type default)
			)
			(layer "B.SilkS")
		)
		(fp_line
			(start 0.7874 0.4064)
			(end 0.7874 -0.4064)
			(stroke
				(width 0.1524)
				(type default)
			)
			(layer "B.SilkS")
		)
		(fp_line
			(start -0.67945 -0.3048)
			(end -0.67945 0.3048)
			(stroke
				(width 0.1)
				(type default)
			)
			(layer "B.Fab")
		)
		(fp_line
			(start -0.67945 0.3048)
			(end -0.120396 0.3048)
			(stroke
				(width 0.1)
				(type default)
			)
			(layer "B.Fab")
		)
		(fp_line
			(start -0.12065 -0.3048)
			(end -0.67945 -0.3048)
			(stroke
				(width 0.1)
				(type default)
			)
			(layer "B.Fab")
		)
		(fp_line
			(start -0.12065 -0.2794)
			(end -0.12065 -0.3048)
			(stroke
				(width 0.1)
				(type default)
			)
			(layer "B.Fab")
		)
		(fp_line
			(start -0.120396 0.2794)
			(end 0.12065 0.2794)
			(stroke
				(width 0.1)
				(type default)
			)
			(layer "B.Fab")
		)
		(fp_line
			(start -0.120396 0.3048)
			(end -0.120396 0.2794)
			(stroke
				(width 0.1)
				(type default)
			)
			(layer "B.Fab")
		)
		(fp_line
			(start 0.12065 -0.305054)
			(end 0.12065 -0.2794)
			(stroke
				(width 0.1)
				(type default)
			)
			(layer "B.Fab")
		)
		(fp_line
			(start 0.12065 -0.2794)
			(end -0.12065 -0.2794)
			(stroke
				(width 0.1)
				(type default)
			)
			(layer "B.Fab")
		)
		(fp_line
			(start 0.12065 0.2794)
			(end 0.12065 0.3048)
			(stroke
				(width 0.1)
				(type default)
			)
			(layer "B.Fab")
		)
		(fp_line
			(start 0.12065 0.3048)
			(end 0.67945 0.3048)
			(stroke
				(width 0.1)
				(type default)
			)
			(layer "B.Fab")
		)
		(fp_line
			(start 0.67945 -0.305054)
			(end 0.12065 -0.305054)
			(stroke
				(width 0.1)
				(type default)
			)
			(layer "B.Fab")
		)
		(fp_line
			(start 0.67945 0.3048)
			(end 0.67945 -0.305054)
			(stroke
				(width 0.1)
				(type default)
			)
			(layer "B.Fab")
		)
		(pad "1" smd circle
			(at 0.40005 0 180)
			(size 0 0)
			(layers "B.Cu" "B.Mask" "B.Paste")
			(net "P3V3_AUX")
		)
		(pad "2" smd circle
			(at -0.40005 0 180)
			(size 0 0)
			(layers "B.Cu" "B.Mask" "B.Paste")
			(net "PWRGD_PVCCINFAON_CPU0_R")
		)
	)
	(footprint ""
		(layer "B.Cu")
		(at 256.271268 -75.32878 90)
		(property "Reference" "R4780"
			(at 0 0 90)
			(layer "B.SilkS")
			(hide yes)
			(effects
				(font
					(size 1.27 1.27)
				)
				(justify mirror)
			)
		)
		(property "Value" ""
			(at 0 0 90)
			(layer "B.Fab")
			(effects
				(font
					(size 1.27 1.27)
				)
				(justify mirror)
			)
		)
		(duplicate_pad_numbers_are_jumpers no)
		(fp_line
			(start 0.7874 -0.4064)
			(end -0.7874 -0.4064)
			(stroke
				(width 0.1524)
				(type default)
			)
			(layer "B.SilkS")
		)
		(fp_line
			(start -0.7874 -0.4064)
			(end -0.7874 0.4064)
			(stroke
				(width 0.1524)
				(type default)
			)
			(layer "B.SilkS")
		)
		(fp_line
			(start 0.7874 0.4064)
			(end 0.7874 -0.4064)
			(stroke
				(width 0.1524)
				(type default)
			)
			(layer "B.SilkS")
		)
		(fp_line
			(start -0.7874 0.4064)
			(end 0.7874 0.4064)
			(stroke
				(width 0.1524)
				(type default)
			)
			(layer "B.SilkS")
		)
		(fp_line
			(start 0.67945 -0.305054)
			(end 0.12065 -0.305054)
			(stroke
				(width 0.1)
				(type default)
			)
			(layer "B.Fab")
		)
		(fp_line
			(start 0.12065 -0.305054)
			(end 0.12065 -0.2794)
			(stroke
				(width 0.1)
				(type default)
			)
			(layer "B.Fab")
		)
		(fp_line
			(start -0.12065 -0.3048)
			(end -0.67945 -0.3048)
			(stroke
				(width 0.1)
				(type default)
			)
			(layer "B.Fab")
		)
		(fp_line
			(start -0.67945 -0.3048)
			(end -0.67945 0.3048)
			(stroke
				(width 0.1)
				(type default)
			)
			(layer "B.Fab")
		)
		(fp_line
			(start 0.12065 -0.2794)
			(end -0.12065 -0.2794)
			(stroke
				(width 0.1)
				(type default)
			)
			(layer "B.Fab")
		)
		(fp_line
			(start -0.12065 -0.2794)
			(end -0.12065 -0.3048)
			(stroke
				(width 0.1)
				(type default)
			)
			(layer "B.Fab")
		)
		(fp_line
			(start 0.12065 0.2794)
			(end 0.12065 0.3048)
			(stroke
				(width 0.1)
				(type default)
			)
			(layer "B.Fab")
		)
		(fp_line
			(start -0.120396 0.2794)
			(end 0.12065 0.2794)
			(stroke
				(width 0.1)
				(type default)
			)
			(layer "B.Fab")
		)
		(fp_line
			(start 0.67945 0.3048)
			(end 0.67945 -0.305054)
			(stroke
				(width 0.1)
				(type default)
			)
			(layer "B.Fab")
		)
		(fp_line
			(start 0.12065 0.3048)
			(end 0.67945 0.3048)
			(stroke
				(width 0.1)
				(type default)
			)
			(layer "B.Fab")
		)
		(fp_line
			(start -0.120396 0.3048)
			(end -0.120396 0.2794)
			(stroke
				(width 0.1)
				(type default)
			)
			(layer "B.Fab")
		)
		(fp_line
			(start -0.67945 0.3048)
			(end -0.120396 0.3048)
			(stroke
				(width 0.1)
				(type default)
			)
			(layer "B.Fab")
		)
		(pad "1" smd circle
			(at 0.40005 0 270)
			(size 0 0)
			(layers "B.Cu" "B.Mask" "B.Paste")
			(net "PWRGD_P1V05_PCH_AUX_R")
		)
		(pad "2" smd circle
			(at -0.40005 0 270)
			(size 0 0)
			(layers "B.Cu" "B.Mask" "B.Paste")
			(net "PWRGD_PVNN_PCH_AUX")
		)
	)
)
